(kicad_pcb
	(version 20241229)
	(generator "pcbnew")
	(generator_version "9.0")
	(general
		(thickness 1.6642)
		(legacy_teardrops no)
	)
	(paper "A3")
	(title_block
		(title "PolarFire SoM")
		(date "2025-07-22")
		(rev "1.1.4")
		(company "Antmicro Ltd")
		(comment 1 "www.antmicro.com")
		(comment 9 "footprints 293-296 of 470")
	)
	(layers
		(0 "F.Cu" mixed)
		(4 "In1.Cu" power)
		(6 "In2.Cu" signal)
		(8 "In3.Cu" power)
		(10 "In4.Cu" signal)
		(12 "In5.Cu" power)
		(14 "In6.Cu" power)
		(16 "In7.Cu" signal)
		(18 "In8.Cu" power)
		(20 "In9.Cu" signal)
		(22 "In10.Cu" power)
		(24 "In11.Cu" signal)
		(26 "In12.Cu" signal)
		(2 "B.Cu" mixed)
		(9 "F.Adhes" user "F.Adhesive")
		(11 "B.Adhes" user "B.Adhesive")
		(13 "F.Paste" user)
		(15 "B.Paste" user)
		(5 "F.SilkS" user "F.Silkscreen")
		(7 "B.SilkS" user "B.Silkscreen")
		(1 "F.Mask" user)
		(3 "B.Mask" user)
		(17 "Dwgs.User" user "User.Drawings")
		(19 "Cmts.User" user "User.Comments")
		(21 "Eco1.User" user "User.Eco1")
		(23 "Eco2.User" user "User.Eco2")
		(25 "Edge.Cuts" user)
		(27 "Margin" user)
		(31 "F.CrtYd" user "F.Courtyard")
		(29 "B.CrtYd" user "B.Courtyard")
		(35 "F.Fab" user)
		(33 "B.Fab" user)
	)
	(footprint "antmicro-footprints:R_0402_1005Metric"
		(layer "B.Cu")
		(at 210.1925 127.347)
		(descr "Resistor SMD 0402")
		(tags "resistor SMD 0402")
		(property "Reference" "R33"
			(at -0.8425 0.628 180)
			(layer "B.SilkS")
			(effects
				(font
					(size 0.7 0.7)
					(thickness 0.15)
				)
				(justify left bottom mirror)
			)
		)
		(property "Value" "R_49k9_0402"
			(at -1.011843 -1.772047 180)
			(layer "B.Fab")
			(hide yes)
			(effects
				(font
					(size 0.7 0.7)
					(thickness 0.15)
				)
				(justify left bottom mirror)
			)
		)
		(property "Datasheet" "https://www.bourns.com/docs/product-datasheets/cr.pdf"
			(at 0 0 0)
			(layer "F.Fab")
			(hide yes)
			(effects
				(font
					(size 1.27 1.27)
					(thickness 0.15)
				)
			)
		)
		(property "Description" "SMD Chip Resistor, 49.9 kohm, ± 1%, 63 mW, 0402 [1005 Metric], Thick Film, General Purpose"
			(at 0 0 0)
			(layer "F.Fab")
			(hide yes)
			(effects
				(font
					(size 1.27 1.27)
					(thickness 0.15)
				)
			)
		)
		(property "Author" "Antmicro"
			(at 0 0 0)
			(layer "B.Fab")
			(hide yes)
			(effects
				(font
					(size 1 1)
					(thickness 0.15)
				)
				(justify mirror)
			)
		)
		(property "License" "Apache-2.0"
			(at 0 0 0)
			(layer "B.Fab")
			(hide yes)
			(effects
				(font
					(size 1 1)
					(thickness 0.15)
				)
				(justify mirror)
			)
		)
		(property "MPN" "CR0402-FX-4992GLF"
			(at 0 0 0)
			(layer "B.Fab")
			(hide yes)
			(effects
				(font
					(size 1 1)
					(thickness 0.15)
				)
				(justify mirror)
			)
		)
		(property "Manufacturer" "Bourns"
			(at 0 0 0)
			(layer "B.Fab")
			(hide yes)
			(effects
				(font
					(size 1 1)
					(thickness 0.15)
				)
				(justify mirror)
			)
		)
		(property "Public" ""
			(at 0 0 0)
			(layer "B.Fab")
			(hide yes)
			(effects
				(font
					(size 1 1)
					(thickness 0.15)
				)
				(justify mirror)
			)
		)
		(property "Tolerance" "1%"
			(at 0 0 0)
			(layer "B.Fab")
			(hide yes)
			(effects
				(font
					(size 1 1)
					(thickness 0.15)
				)
				(justify mirror)
			)
		)
		(property "Val" "49k9"
			(at 0 0 0)
			(layer "B.Fab")
			(hide yes)
			(effects
				(font
					(size 1 1)
					(thickness 0.15)
				)
				(justify mirror)
			)
		)
		(sheetname "/Memory/")
		(sheetfile "memory.kicad_sch")
		(attr smd)
		(fp_rect
			(start -0.925 0.47)
			(end 0.925 -0.47)
			(stroke
				(width 0.05)
				(type default)
			)
			(fill no)
			(layer "B.CrtYd")
		)
		(fp_rect
			(start -0.5 0.25)
			(end 0.5 -0.25)
			(stroke
				(width 0.15)
				(type solid)
			)
			(fill no)
			(layer "B.Fab")
		)
		(fp_text user "License: Apache-2.0"
			(at -0.95 -5.169 180)
			(layer "B.Fab")
			(effects
				(font
					(size 0.7 0.7)
					(thickness 0.15)
				)
				(justify left bottom mirror)
			)
		)
		(fp_text user "${REFERENCE}"
			(at -0.95 -3.168 180)
			(layer "B.Fab")
			(effects
				(font
					(size 0.7 0.7)
					(thickness 0.15)
				)
				(justify left bottom mirror)
			)
		)
		(fp_text user "Author: Antmicro"
			(at -0.95 -4.169 180)
			(layer "B.Fab")
			(effects
				(font
					(size 0.7 0.7)
					(thickness 0.15)
				)
				(justify left bottom mirror)
			)
		)
		(pad "1" smd roundrect
			(at -0.48 0)
			(size 0.59 0.64)
			(layers "B.Cu" "B.Mask" "B.Paste")
			(roundrect_rratio 0.25)
			(net 213 "/FPGA MSSIO/EMMC.DAT5")
			(pintype "passive")
		)
		(pad "2" smd roundrect
			(at 0.48 0)
			(size 0.59 0.64)
			(layers "B.Cu" "B.Mask" "B.Paste")
			(roundrect_rratio 0.25)
			(net 137 "SD_VDD")
			(pintype "passive")
		)
	)
	(footprint "antmicro-footprints:R_0402_1005Metric"
		(layer "B.Cu")
		(at 193.95 123.25 180)
		(descr "Resistor SMD 0402")
		(tags "resistor SMD 0402")
		(property "Reference" "R75"
			(at -1.1 1.6 0)
			(layer "B.SilkS")
			(effects
				(font
					(size 0.7 0.7)
					(thickness 0.15)
				)
				(justify left bottom mirror)
			)
		)
		(property "Value" "R_1k_0402"
			(at -1.011843 -1.772047 0)
			(layer "B.Fab")
			(hide yes)
			(effects
				(font
					(size 0.7 0.7)
					(thickness 0.15)
				)
				(justify left bottom mirror)
			)
		)
		(property "Datasheet" "https://www.bourns.com/docs/product-datasheets/cr.pdf"
			(at 0 0 180)
			(layer "F.Fab")
			(hide yes)
			(effects
				(font
					(size 1.27 1.27)
					(thickness 0.15)
				)
			)
		)
		(property "Description" "SMD Chip Resistor, 1 kohm, ± 1%, 63 mW, 0402 [1005 Metric], Thick Film, General Purpose"
			(at 0 0 180)
			(layer "F.Fab")
			(hide yes)
			(effects
				(font
					(size 1.27 1.27)
					(thickness 0.15)
				)
			)
		)
		(property "Author" "Antmicro"
			(at 387.9 246.5 0)
			(layer "B.Fab")
			(hide yes)
			(effects
				(font
					(size 1 1)
					(thickness 0.15)
				)
				(justify mirror)
			)
		)
		(property "License" "Apache-2.0"
			(at 387.9 246.5 0)
			(layer "B.Fab")
			(hide yes)
			(effects
				(font
					(size 1 1)
					(thickness 0.15)
				)
				(justify mirror)
			)
		)
		(property "MPN" "CR0402-FX-1001GLF"
			(at 387.9 246.5 0)
			(layer "B.Fab")
			(hide yes)
			(effects
				(font
					(size 1 1)
					(thickness 0.15)
				)
				(justify mirror)
			)
		)
		(property "Manufacturer" "Bourns"
			(at 387.9 246.5 0)
			(layer "B.Fab")
			(hide yes)
			(effects
				(font
					(size 1 1)
					(thickness 0.15)
				)
				(justify mirror)
			)
		)
		(property "Public" ""
			(at 387.9 246.5 0)
			(layer "B.Fab")
			(hide yes)
			(effects
				(font
					(size 1 1)
					(thickness 0.15)
				)
				(justify mirror)
			)
		)
		(property "Tolerance" "1%"
			(at 387.9 246.5 0)
			(layer "B.Fab")
			(hide yes)
			(effects
				(font
					(size 1 1)
					(thickness 0.15)
				)
				(justify mirror)
			)
		)
		(property "Val" "1k"
			(at 387.9 246.5 0)
			(layer "B.Fab")
			(hide yes)
			(effects
				(font
					(size 1 1)
					(thickness 0.15)
				)
				(justify mirror)
			)
		)
		(sheetname "/FPGA MSS/")
		(sheetfile "fpga-mss.kicad_sch")
		(attr smd)
		(fp_rect
			(start -0.925 0.47)
			(end 0.925 -0.47)
			(stroke
				(width 0.05)
				(type default)
			)
			(fill no)
			(layer "B.CrtYd")
		)
		(fp_rect
			(start -0.5 0.25)
			(end 0.5 -0.25)
			(stroke
				(width 0.15)
				(type solid)
			)
			(fill no)
			(layer "B.Fab")
		)
		(fp_text user "${REFERENCE}"
			(at -0.95 -3.168 0)
			(layer "B.Fab")
			(effects
				(font
					(size 0.7 0.7)
					(thickness 0.15)
				)
				(justify left bottom mirror)
			)
		)
		(fp_text user "License: Apache-2.0"
			(at -0.95 -5.169 0)
			(layer "B.Fab")
			(effects
				(font
					(size 0.7 0.7)
					(thickness 0.15)
				)
				(justify left bottom mirror)
			)
		)
		(fp_text user "Author: Antmicro"
			(at -0.95 -4.169 0)
			(layer "B.Fab")
			(effects
				(font
					(size 0.7 0.7)
					(thickness 0.15)
				)
				(justify left bottom mirror)
			)
		)
		(pad "1" smd roundrect
			(at -0.48 0 180)
			(size 0.59 0.64)
			(layers "B.Cu" "B.Mask" "B.Paste")
			(roundrect_rratio 0.25)
			(net 417 "GND")
			(pintype "passive")
		)
		(pad "2" smd roundrect
			(at 0.48 0 180)
			(size 0.59 0.64)
			(layers "B.Cu" "B.Mask" "B.Paste")
			(roundrect_rratio 0.25)
			(net 270 "Net-(U1G-MSS_DDR_VREF_IN)")
			(pintype "passive")
		)
	)
	(footprint "antmicro-footprints:XSON-8_1x1.95mm_P0.5mm"
		(layer "B.Cu")
		(at 221.04 141.62)
		(property "Reference" "U27"
			(at -1.23 2.17 0)
			(layer "B.SilkS")
			(effects
				(font
					(size 0.7 0.7)
					(thickness 0.15)
				)
				(justify right bottom mirror)
			)
		)
		(property "Value" "NTS0102_XSON"
			(at 0 -2.2 0)
			(layer "B.Fab")
			(hide yes)
			(effects
				(font
					(size 0.7 0.7)
					(thickness 0.15)
				)
				(justify right bottom mirror)
			)
		)
		(property "Datasheet" "http://www.farnell.com/datasheets/1760723.pdf"
			(at 0 0 0)
			(layer "F.Fab")
			(hide yes)
			(effects
				(font
					(size 1.27 1.27)
					(thickness 0.15)
				)
			)
		)
		(property "Description" "Transceiver, 1.65 V to 3.6 V, XSON-8"
			(at 0 0 0)
			(layer "F.Fab")
			(hide yes)
			(effects
				(font
					(size 1.27 1.27)
					(thickness 0.15)
				)
			)
		)
		(property "Author" "Antmicro"
			(at 0 0 0)
			(layer "B.Fab")
			(hide yes)
			(effects
				(font
					(size 1 1)
					(thickness 0.15)
				)
				(justify mirror)
			)
		)
		(property "License" "Apache-2.0"
			(at 0 0 0)
			(layer "B.Fab")
			(hide yes)
			(effects
				(font
					(size 1 1)
					(thickness 0.15)
				)
				(justify mirror)
			)
		)
		(property "MPN" "NTS0102GT"
			(at 0 0 0)
			(layer "B.Fab")
			(hide yes)
			(effects
				(font
					(size 1 1)
					(thickness 0.15)
				)
				(justify mirror)
			)
		)
		(property "Manufacturer" "NXP"
			(at 0 0 0)
			(layer "B.Fab")
			(hide yes)
			(effects
				(font
					(size 1 1)
					(thickness 0.15)
				)
				(justify mirror)
			)
		)
		(sheetname "/FPGA GPIO/")
		(sheetfile "fpga-gpio.kicad_sch")
		(attr smd)
		(fp_line
			(start -0.5 1.1)
			(end 0.5 1.1)
			(stroke
				(width 0.15)
				(type solid)
			)
			(layer "B.SilkS")
		)
		(fp_line
			(start 0.5 -1.1)
			(end -0.5 -1.1)
			(stroke
				(width 0.15)
				(type solid)
			)
			(layer "B.SilkS")
		)
		(fp_circle
			(center -0.75 1.1)
			(end -0.701 1.1)
			(stroke
				(width 0.15)
				(type solid)
			)
			(fill no)
			(layer "B.SilkS")
		)
		(fp_rect
			(start -0.8 1.2)
			(end 0.8 -1.2)
			(stroke
				(width 0.05)
				(type solid)
			)
			(fill no)
			(layer "B.CrtYd")
		)
		(fp_line
			(start -0.5305 -1)
			(end -0.5305 1.001)
			(stroke
				(width 0.15)
				(type solid)
			)
			(layer "B.Fab")
		)
		(fp_line
			(start -0.5305 1.001)
			(end 0.5305 1.001)
			(stroke
				(width 0.15)
				(type solid)
			)
			(layer "B.Fab")
		)
		(fp_line
			(start 0.5305 -1)
			(end -0.5305 -1)
			(stroke
				(width 0.15)
				(type solid)
			)
			(layer "B.Fab")
		)
		(fp_line
			(start 0.5305 1.001)
			(end 0.5305 -1)
			(stroke
				(width 0.15)
				(type solid)
			)
			(layer "B.Fab")
		)
		(fp_text user "${REFERENCE}"
			(at -0.527 -5.905 180)
			(layer "B.Fab")
			(effects
				(font
					(size 0.7 0.7)
					(thickness 0.15)
				)
				(justify left bottom mirror)
			)
		)
		(fp_text user "License: Apache-2.0"
			(at -0.527 -8.306 180)
			(layer "B.Fab")
			(effects
				(font
					(size 0.7 0.7)
					(thickness 0.15)
				)
				(justify left bottom mirror)
			)
		)
		(fp_text user "Author: Antmicro"
			(at -0.527 -7.105 180)
			(layer "B.Fab")
			(effects
				(font
					(size 0.7 0.7)
					(thickness 0.15)
				)
				(justify left bottom mirror)
			)
		)
		(pad "1" smd roundrect
			(at -0.45 0.75 180)
			(size 0.6 0.3)
			(layers "B.Cu" "B.Mask" "B.Paste")
			(roundrect_rratio 0.25)
			(net 128 "/FPGA GPIO/WiFi.DAT3")
			(pinfunction "B_{2}")
			(pintype "bidirectional")
		)
		(pad "2" smd roundrect
			(at -0.45 0.25 180)
			(size 0.6 0.25)
			(layers "B.Cu" "B.Mask" "B.Paste")
			(roundrect_rratio 0.25)
			(net 417 "GND")
			(pinfunction "GND")
			(pintype "power_in")
		)
		(pad "3" smd roundrect
			(at -0.45 -0.25 180)
			(size 0.6 0.25)
			(layers "B.Cu" "B.Mask" "B.Paste")
			(roundrect_rratio 0.25)
			(net 649 "VDD")
			(pinfunction "VCC_{A}")
			(pintype "power_in")
		)
		(pad "4" smd roundrect
			(at -0.45 -0.75 180)
			(size 0.6 0.3)
			(layers "B.Cu" "B.Mask" "B.Paste")
			(roundrect_rratio 0.25)
			(net 351 "/FPGA GPIO/WiFi_DATA_3")
			(pinfunction "A_{2}")
			(pintype "bidirectional")
		)
		(pad "5" smd roundrect
			(at 0.45 -0.75 180)
			(size 0.6 0.3)
			(layers "B.Cu" "B.Mask" "B.Paste")
			(roundrect_rratio 0.25)
			(net 374 "/FPGA GPIO/WiFi_DATA_0")
			(pinfunction "A_{1}")
			(pintype "bidirectional")
		)
		(pad "6" smd roundrect
			(at 0.45 -0.25 180)
			(size 0.6 0.25)
			(layers "B.Cu" "B.Mask" "B.Paste")
			(roundrect_rratio 0.25)
			(net 649 "VDD")
			(pinfunction "OE")
			(pintype "input")
		)
		(pad "7" smd roundrect
			(at 0.45 0.25 180)
			(size 0.6 0.25)
			(layers "B.Cu" "B.Mask" "B.Paste")
			(roundrect_rratio 0.25)
			(net 50 "+3V3")
			(pinfunction "VCC_{B}")
			(pintype "power_in")
		)
		(pad "8" smd roundrect
			(at 0.45 0.75 180)
			(size 0.6 0.3)
			(layers "B.Cu" "B.Mask" "B.Paste")
			(roundrect_rratio 0.25)
			(net 240 "/FPGA GPIO/WiFi.DAT0")
			(pinfunction "B_{1}")
			(pintype "bidirectional")
		)
	)
	(footprint "antmicro-footprints:C_0402_1005Metric"
		(layer "B.Cu")
		(at 208.1 146.475 180)
		(descr "Capacitor SMD 0402")
		(tags "capacitor SMD 0402")
		(property "Reference" "C196"
			(at 4.9 18.375 0)
			(layer "B.SilkS")
			(effects
				(font
					(size 0.7 0.7)
					(thickness 0.15)
				)
				(justify left bottom mirror)
			)
		)
		(property "Value" "C_10u_10V_0402"
			(at -1.022927 -2.155213 0)
			(layer "B.Fab")
			(hide yes)
			(effects
				(font
					(size 0.7 0.7)
					(thickness 0.15)
				)
				(justify left bottom mirror)
			)
		)
		(property "Datasheet" "https://www.murata.com/products/productdetail?partno=GRM155R61A106ME11%23"
			(at 0 0 180)
			(layer "F.Fab")
			(hide yes)
			(effects
				(font
					(size 1.27 1.27)
					(thickness 0.15)
				)
			)
		)
		(property "Description" "Multilayer Ceramic Capacitors MLCC - SMD/SMT 10 uF 10 VDC 20% 0402 X5R"
			(at 0 0 180)
			(layer "F.Fab")
			(hide yes)
			(effects
				(font
					(size 1.27 1.27)
					(thickness 0.15)
				)
			)
		)
		(property "Author" "Antmicro"
			(at 416.2 292.95 0)
			(layer "B.Fab")
			(hide yes)
			(effects
				(font
					(size 1 1)
					(thickness 0.15)
				)
				(justify mirror)
			)
		)
		(property "Dielectric" "X5R"
			(at 416.2 292.95 0)
			(layer "B.Fab")
			(hide yes)
			(effects
				(font
					(size 1 1)
					(thickness 0.15)
				)
				(justify mirror)
			)
		)
		(property "License" "Apache-2.0"
			(at 416.2 292.95 0)
			(layer "B.Fab")
			(hide yes)
			(effects
				(font
					(size 1 1)
					(thickness 0.15)
				)
				(justify mirror)
			)
		)
		(property "MPN" "GRM155R61A106ME11D"
			(at 416.2 292.95 0)
			(layer "B.Fab")
			(hide yes)
			(effects
				(font
					(size 1 1)
					(thickness 0.15)
				)
				(justify mirror)
			)
		)
		(property "Manufacturer" "Murata"
			(at 416.2 292.95 0)
			(layer "B.Fab")
			(hide yes)
			(effects
				(font
					(size 1 1)
					(thickness 0.15)
				)
				(justify mirror)
			)
		)
		(property "Public" ""
			(at 416.2 292.95 0)
			(layer "B.Fab")
			(hide yes)
			(effects
				(font
					(size 1 1)
					(thickness 0.15)
				)
				(justify mirror)
			)
		)
		(property "Val" "10u"
			(at 416.2 292.95 0)
			(layer "B.Fab")
			(hide yes)
			(effects
				(font
					(size 1 1)
					(thickness 0.15)
				)
				(justify mirror)
			)
		)
		(property "Voltage" "10V"
			(at 416.2 292.95 0)
			(layer "B.Fab")
			(hide yes)
			(effects
				(font
					(size 1 1)
					(thickness 0.15)
				)
				(justify mirror)
			)
		)
		(sheetname "/MIPI CrossLink/")
		(sheetfile "crosslink.kicad_sch")
		(attr smd)
		(fp_rect
			(start -0.925 0.47)
			(end 0.925 -0.47)
			(stroke
				(width 0.05)
				(type default)
			)
			(fill no)
			(layer "B.CrtYd")
		)
		(fp_line
			(start 0.504 0.25)
			(end 0.504 -0.248)
			(stroke
				(width 0.15)
				(type solid)
			)
			(layer "B.Fab")
		)
		(fp_line
			(start 0.504 -0.248)
			(end -0.494 -0.248)
			(stroke
				(width 0.15)
				(type solid)
			)
			(layer "B.Fab")
		)
		(fp_line
			(start -0.494 0.25)
			(end 0.504 0.25)
			(stroke
				(width 0.15)
				(type solid)
			)
			(layer "B.Fab")
		)
		(fp_line
			(start -0.494 -0.248)
			(end -0.494 0.25)
			(stroke
				(width 0.15)
				(type solid)
			)
			(layer "B.Fab")
		)
		(fp_text user "${REFERENCE}"
			(at -0.939 -4.599 0)
			(layer "B.Fab")
			(effects
				(font
					(size 0.7 0.7)
					(thickness 0.15)
				)
				(justify left bottom mirror)
			)
		)
		(fp_text user "Author: Antmicro"
			(at -0.939 -3.399 0)
			(layer "B.Fab")
			(effects
				(font
					(size 0.7 0.7)
					(thickness 0.15)
				)
				(justify left bottom mirror)
			)
		)
		(fp_text user "License: Apache-2.0"
			(at -0.939 -5.799 0)
			(layer "B.Fab")
			(effects
				(font
					(size 0.7 0.7)
					(thickness 0.15)
				)
				(justify left bottom mirror)
			)
		)
		(pad "1" smd roundrect
			(at -0.48 0 180)
			(size 0.59 0.64)
			(layers "B.Cu" "B.Mask" "B.Paste")
			(roundrect_rratio 0.25)
			(net 417 "GND")
			(pintype "passive")
		)
		(pad "2" smd roundrect
			(at 0.48 0 180)
			(size 0.59 0.64)
			(layers "B.Cu" "B.Mask" "B.Paste")
			(roundrect_rratio 0.25)
			(net 183 "/MIPI CrossLink/CL_VCCIO0")
			(pintype "passive")
		)
	)
)
